(kicad_pcb
	(version 20260206)
	(generator "pcbnew")
	(generator_version "10.0")
	(general
		(thickness 1.6)
		(legacy_teardrops no)
	)
	(paper "A4")
	(title_block
		(title "baseboard — 13948-1b.1110WZS1818.brd")
		(comment 1 "Honey Badger (Wiwynn) / footprints 1511-1518 of 2523")
	)
	(layers
		(0 "F.Cu" signal "TOP")
		(4 "In1.Cu" signal "L2GND")
		(6 "In2.Cu" signal "L3")
		(8 "In3.Cu" signal "L4VCC")
		(10 "In4.Cu" signal "L5VCC")
		(12 "In5.Cu" signal "L6")
		(14 "In6.Cu" signal "L7GND")
		(2 "B.Cu" signal "BOTTOM")
		(9 "F.Adhes" user "F.Adhesive")
		(11 "B.Adhes" user "B.Adhesive")
		(13 "F.Paste" user "Package Geometry/Pastemask Top")
		(15 "B.Paste" user "Package Geometry/Pastemask Bottom")
		(5 "F.SilkS" user "Ref Des/Silkscreen Top")
		(7 "B.SilkS" user "Ref Des/Silkscreen Bottom")
		(1 "F.Mask" user "Board Geometry/Soldermask Top")
		(3 "B.Mask" user "Board Geometry/Soldermask Bottom")
		(17 "Dwgs.User" user "User.Drawings")
		(19 "Cmts.User" user "User.Comments")
		(21 "Eco1.User" user "User.Eco1")
		(23 "Eco2.User" user "User.Eco2")
		(25 "Edge.Cuts" user "Board Geometry/Outline")
		(27 "Margin" user)
		(31 "F.CrtYd" user "Package Geometry/Place Bound Top")
		(29 "B.CrtYd" user "Package Geometry/Place Bound Bottom")
		(35 "F.Fab" user "Ref Des/Assembly Top")
		(33 "B.Fab" user "Ref Des/Assembly Bottom")
	)
	(footprint ""
		(layer "F.Cu")
		(at 347.345 -94.361 90)
		(property "Reference" "PC17"
			(at 0 0 90)
			(layer "F.SilkS")
			(hide yes)
			(effects
				(font
					(size 1.27 1.27)
				)
			)
		)
		(property "Value" "SC47U10V6MX-GP"
			(at -0.0762 -5.1308 90)
			(unlocked yes)
			(layer "F.Fab")
			(hide yes)
			(effects
				(font
					(size 1.016 1.016)
					(thickness 0.1524)
				)
			)
		)
		(property "Device Type" "C1206H71"
			(at -0.127 -6.6548 90)
			(unlocked yes)
			(layer "F.Fab")
			(hide yes)
			(effects
				(font
					(size 1.016 1.016)
					(thickness 0.1524)
				)
			)
		)
		(duplicate_pad_numbers_are_jumpers no)
		(fp_line
			(start 1.016 -2.2352)
			(end 1.016 -0.8382)
			(stroke
				(width 0.1524)
				(type default)
			)
			(layer "F.SilkS")
		)
		(fp_line
			(start -1.016 -2.2352)
			(end 1.016 -2.2352)
			(stroke
				(width 0.1524)
				(type default)
			)
			(layer "F.SilkS")
		)
		(fp_line
			(start -1.016 -0.8382)
			(end -1.016 -2.2352)
			(stroke
				(width 0.1524)
				(type default)
			)
			(layer "F.SilkS")
		)
		(fp_line
			(start 1.016 0.8382)
			(end 1.016 2.2352)
			(stroke
				(width 0.1524)
				(type default)
			)
			(layer "F.SilkS")
		)
		(fp_line
			(start 1.016 2.2352)
			(end -1.016 2.2352)
			(stroke
				(width 0.1524)
				(type default)
			)
			(layer "F.SilkS")
		)
		(fp_line
			(start -1.016 2.2352)
			(end -1.016 0.8382)
			(stroke
				(width 0.1524)
				(type default)
			)
			(layer "F.SilkS")
		)
		(fp_rect
			(start -1.0922 2.3114)
			(end 1.0922 -2.3114)
			(stroke
				(width 0)
				(type default)
			)
			(fill no)
			(layer "F.CrtYd")
		)
		(fp_poly
			(pts
				(xy 1.0922 -2.3114) (xy 1.0922 2.3114) (xy -1.0922 2.3114) (xy -1.0922 -2.3114)
			)
			(stroke
				(width 0)
				(type default)
			)
			(fill no)
			(layer "F.Fab")
		)
		(pad "1" smd rect
			(at 0 -1.397 90)
			(size 1.651 1.27)
			(layers "F.Cu" "F.Mask" "F.Paste")
			(net "P5V_STBY")
		)
		(pad "2" smd rect
			(at 0 1.397 90)
			(size 1.651 1.27)
			(layers "F.Cu" "F.Mask" "F.Paste")
			(net "GND")
		)
	)
	(footprint ""
		(layer "F.Cu")
		(at 95.70847 -108.331 -90)
		(property "Reference" "SR735"
			(at 0 0 270)
			(layer "F.SilkS")
			(hide yes)
			(effects
				(font
					(size 1.27 1.27)
				)
			)
		)
		(property "Value" "2K2R2F-GP"
			(at 0.064008 -3.993896 270)
			(unlocked yes)
			(layer "F.Fab")
			(hide yes)
			(effects
				(font
					(size 1.016 1.016)
					(thickness 0.1524)
				)
			)
		)
		(property "Device Type" "R402H16"
			(at 0.064008 -5.517896 270)
			(unlocked yes)
			(layer "F.Fab")
			(hide yes)
			(effects
				(font
					(size 1.016 1.016)
					(thickness 0.1524)
				)
			)
		)
		(duplicate_pad_numbers_are_jumpers no)
		(fp_line
			(start -0.508 -0.9398)
			(end -0.508 0.9398)
			(stroke
				(width 0.1524)
				(type default)
			)
			(layer "F.SilkS")
		)
		(fp_line
			(start 0.508 -0.9398)
			(end -0.508 -0.9398)
			(stroke
				(width 0.1524)
				(type default)
			)
			(layer "F.SilkS")
		)
		(fp_rect
			(start -0.508 0.9398)
			(end 0.508 -0.9398)
			(stroke
				(width 0)
				(type default)
			)
			(fill no)
			(layer "F.CrtYd")
		)
		(fp_rect
			(start -0.508 0.9398)
			(end 0.508 -0.9398)
			(stroke
				(width 0)
				(type default)
			)
			(fill no)
			(layer "F.Fab")
		)
		(pad "1" smd custom
			(at 0 -0.4445 270)
			(size 0.1397 0.1397)
			(layers "F.Cu" "F.Mask" "F.Paste")
			(net "EXP_I2C_SDA_4")
			(options
				(clearance outline)
				(anchor circle)
			)
			(primitives
				(gr_poly
					(pts
						(arc
							(start -0.1778 -0.2794)
							(mid -0.249642 -0.249642)
							(end -0.2794 -0.1778)
						)
						(arc
							(start -0.2794 0.1778)
							(mid -0.249642 0.249642)
							(end -0.1778 0.2794)
						)
						(arc
							(start 0.1778 0.2794)
							(mid 0.249642 0.249642)
							(end 0.2794 0.1778)
						)
						(arc
							(start 0.2794 -0.1778)
							(mid 0.249642 -0.249642)
							(end 0.1778 -0.2794)
						)
					)
					(width 0)
					(fill yes)
				)
			)
		)
		(pad "2" smd custom
			(at 0 0.4445 270)
			(size 0.1397 0.1397)
			(layers "F.Cu" "F.Mask" "F.Paste")
			(net "P1V8_E")
			(options
				(clearance outline)
				(anchor circle)
			)
			(primitives
				(gr_poly
					(pts
						(arc
							(start -0.1778 -0.2794)
							(mid -0.249642 -0.249642)
							(end -0.2794 -0.1778)
						)
						(arc
							(start -0.2794 0.1778)
							(mid -0.249642 0.249642)
							(end -0.1778 0.2794)
						)
						(arc
							(start 0.1778 0.2794)
							(mid 0.249642 0.249642)
							(end 0.2794 0.1778)
						)
						(arc
							(start 0.2794 -0.1778)
							(mid 0.249642 -0.249642)
							(end 0.1778 -0.2794)
						)
					)
					(width 0)
					(fill yes)
				)
			)
		)
	)
	(footprint ""
		(layer "F.Cu")
		(at 107.442 -68.072 -90)
		(property "Reference" "SR865"
			(at 0 0 270)
			(layer "F.SilkS")
			(hide yes)
			(effects
				(font
					(size 1.27 1.27)
				)
			)
		)
		(property "Value" "0R2J-2-GP"
			(at 0.064008 -3.993896 270)
			(unlocked yes)
			(layer "F.Fab")
			(hide yes)
			(effects
				(font
					(size 1.016 1.016)
					(thickness 0.1524)
				)
			)
		)
		(property "Device Type" "R402H16"
			(at 0.064008 -5.517896 270)
			(unlocked yes)
			(layer "F.Fab")
			(hide yes)
			(effects
				(font
					(size 1.016 1.016)
					(thickness 0.1524)
				)
			)
		)
		(duplicate_pad_numbers_are_jumpers no)
		(fp_line
			(start -0.508 -0.9398)
			(end -0.508 0.9398)
			(stroke
				(width 0.1524)
				(type default)
			)
			(layer "F.SilkS")
		)
		(fp_line
			(start 0.508 -0.9398)
			(end -0.508 -0.9398)
			(stroke
				(width 0.1524)
				(type default)
			)
			(layer "F.SilkS")
		)
		(fp_rect
			(start -0.508 0.9398)
			(end 0.508 -0.9398)
			(stroke
				(width 0)
				(type default)
			)
			(fill no)
			(layer "F.CrtYd")
		)
		(fp_rect
			(start -0.508 0.9398)
			(end 0.508 -0.9398)
			(stroke
				(width 0)
				(type default)
			)
			(fill no)
			(layer "F.Fab")
		)
		(pad "1" smd custom
			(at 0 -0.4445 270)
			(size 0.1397 0.1397)
			(layers "F.Cu" "F.Mask" "F.Paste")
			(net "JTAG_IOC_TMS")
			(options
				(clearance outline)
				(anchor circle)
			)
			(primitives
				(gr_poly
					(pts
						(arc
							(start -0.1778 -0.2794)
							(mid -0.249642 -0.249642)
							(end -0.2794 -0.1778)
						)
						(arc
							(start -0.2794 0.1778)
							(mid -0.249642 0.249642)
							(end -0.1778 0.2794)
						)
						(arc
							(start 0.1778 0.2794)
							(mid 0.249642 0.249642)
							(end 0.2794 0.1778)
						)
						(arc
							(start 0.2794 -0.1778)
							(mid 0.249642 -0.249642)
							(end 0.1778 -0.2794)
						)
					)
					(width 0)
					(fill yes)
				)
			)
		)
		(pad "2" smd custom
			(at 0 0.4445 270)
			(size 0.1397 0.1397)
			(layers "F.Cu" "F.Mask" "F.Paste")
			(net "JTAG_EXP_IOC_TMS")
			(options
				(clearance outline)
				(anchor circle)
			)
			(primitives
				(gr_poly
					(pts
						(arc
							(start -0.1778 -0.2794)
							(mid -0.249642 -0.249642)
							(end -0.2794 -0.1778)
						)
						(arc
							(start -0.2794 0.1778)
							(mid -0.249642 0.249642)
							(end -0.1778 0.2794)
						)
						(arc
							(start 0.1778 0.2794)
							(mid 0.249642 0.249642)
							(end 0.2794 0.1778)
						)
						(arc
							(start 0.2794 -0.1778)
							(mid 0.249642 -0.249642)
							(end 0.1778 -0.2794)
						)
					)
					(width 0)
					(fill yes)
				)
			)
		)
	)
	(footprint ""
		(layer "F.Cu")
		(at 317.881 -52.197 90)
		(property "Reference" "C280"
			(at 0 0 90)
			(layer "F.SilkS")
			(hide yes)
			(effects
				(font
					(size 1.27 1.27)
				)
			)
		)
		(property "Value" "SCD1U25V2KX-2-GP"
			(at 1.1811 -2.7051 90)
			(unlocked yes)
			(layer "F.Fab")
			(hide yes)
			(effects
				(font
					(size 1.016 1.016)
					(thickness 0.1524)
				)
			)
		)
		(property "Device Type" "C402H22"
			(at 1.1811 -4.2291 90)
			(unlocked yes)
			(layer "F.Fab")
			(hide yes)
			(effects
				(font
					(size 1.016 1.016)
					(thickness 0.1524)
				)
			)
		)
		(duplicate_pad_numbers_are_jumpers no)
		(fp_rect
			(start -0.4318 0.9525)
			(end 0.4318 -0.9525)
			(stroke
				(width 0)
				(type default)
			)
			(fill no)
			(layer "F.CrtYd")
		)
		(fp_rect
			(start -0.4318 0.9525)
			(end 0.4318 -0.9525)
			(stroke
				(width 0)
				(type default)
			)
			(fill no)
			(layer "F.Fab")
		)
		(pad "1" smd custom
			(at 0 -0.4445 90)
			(size 0.1524 0.1524)
			(layers "F.Cu" "F.Mask" "F.Paste")
			(net "P5V_STBY")
			(options
				(clearance outline)
				(anchor circle)
			)
			(primitives
				(gr_poly
					(pts
						(arc
							(start 0.3048 -0.2032)
							(mid 0.275042 -0.275042)
							(end 0.2032 -0.3048)
						)
						(arc
							(start -0.2032 -0.3048)
							(mid -0.275042 -0.275042)
							(end -0.3048 -0.2032)
						)
						(arc
							(start -0.3048 0.2032)
							(mid -0.275042 0.275042)
							(end -0.2032 0.3048)
						)
						(arc
							(start 0.2032 0.3048)
							(mid 0.275042 0.275042)
							(end 0.3048 0.2032)
						)
					)
					(width 0)
					(fill yes)
				)
			)
		)
		(pad "2" smd custom
			(at 0 0.4445 90)
			(size 0.1524 0.1524)
			(layers "F.Cu" "F.Mask" "F.Paste")
			(net "GND")
			(options
				(clearance outline)
				(anchor circle)
			)
			(primitives
				(gr_poly
					(pts
						(arc
							(start 0.3048 -0.2032)
							(mid 0.275042 -0.275042)
							(end 0.2032 -0.3048)
						)
						(arc
							(start -0.2032 -0.3048)
							(mid -0.275042 -0.275042)
							(end -0.3048 -0.2032)
						)
						(arc
							(start -0.3048 0.2032)
							(mid -0.275042 0.275042)
							(end -0.2032 0.3048)
						)
						(arc
							(start 0.2032 0.3048)
							(mid 0.275042 0.275042)
							(end 0.3048 0.2032)
						)
					)
					(width 0)
					(fill yes)
				)
			)
		)
	)
	(footprint ""
		(layer "F.Cu")
		(at 193.167 -15.113 -90)
		(property "Reference" "R190"
			(at 0 0 270)
			(layer "F.SilkS")
			(hide yes)
			(effects
				(font
					(size 1.27 1.27)
				)
			)
		)
		(property "Value" "0R2J-2-GP"
			(at 0.064008 -3.993896 270)
			(unlocked yes)
			(layer "F.Fab")
			(hide yes)
			(effects
				(font
					(size 1.016 1.016)
					(thickness 0.1524)
				)
			)
		)
		(property "Device Type" "R402H16"
			(at 0.064008 -5.517896 270)
			(unlocked yes)
			(layer "F.Fab")
			(hide yes)
			(effects
				(font
					(size 1.016 1.016)
					(thickness 0.1524)
				)
			)
		)
		(duplicate_pad_numbers_are_jumpers no)
		(fp_line
			(start -0.508 -0.9398)
			(end -0.508 0.9398)
			(stroke
				(width 0.1524)
				(type default)
			)
			(layer "F.SilkS")
		)
		(fp_line
			(start 0.508 -0.9398)
			(end -0.508 -0.9398)
			(stroke
				(width 0.1524)
				(type default)
			)
			(layer "F.SilkS")
		)
		(fp_rect
			(start -0.508 0.9398)
			(end 0.508 -0.9398)
			(stroke
				(width 0)
				(type default)
			)
			(fill no)
			(layer "F.CrtYd")
		)
		(fp_rect
			(start -0.508 0.9398)
			(end 0.508 -0.9398)
			(stroke
				(width 0)
				(type default)
			)
			(fill no)
			(layer "F.Fab")
		)
		(pad "1" smd custom
			(at 0 -0.4445 270)
			(size 0.1397 0.1397)
			(layers "F.Cu" "F.Mask" "F.Paste")
			(net "BMC_I2C_D_SCL")
			(options
				(clearance outline)
				(anchor circle)
			)
			(primitives
				(gr_poly
					(pts
						(arc
							(start -0.1778 -0.2794)
							(mid -0.249642 -0.249642)
							(end -0.2794 -0.1778)
						)
						(arc
							(start -0.2794 0.1778)
							(mid -0.249642 0.249642)
							(end -0.1778 0.2794)
						)
						(arc
							(start 0.1778 0.2794)
							(mid 0.249642 0.249642)
							(end 0.2794 0.1778)
						)
						(arc
							(start 0.2794 -0.1778)
							(mid 0.249642 -0.249642)
							(end 0.1778 -0.2794)
						)
					)
					(width 0)
					(fill yes)
				)
			)
		)
		(pad "2" smd custom
			(at 0 0.4445 270)
			(size 0.1397 0.1397)
			(layers "F.Cu" "F.Mask" "F.Paste")
			(net "TEMP_1_SCL")
			(options
				(clearance outline)
				(anchor circle)
			)
			(primitives
				(gr_poly
					(pts
						(arc
							(start -0.1778 -0.2794)
							(mid -0.249642 -0.249642)
							(end -0.2794 -0.1778)
						)
						(arc
							(start -0.2794 0.1778)
							(mid -0.249642 0.249642)
							(end -0.1778 0.2794)
						)
						(arc
							(start 0.1778 0.2794)
							(mid 0.249642 0.249642)
							(end 0.2794 0.1778)
						)
						(arc
							(start 0.2794 -0.1778)
							(mid 0.249642 -0.249642)
							(end 0.1778 -0.2794)
						)
					)
					(width 0)
					(fill yes)
				)
			)
		)
	)
	(footprint ""
		(layer "F.Cu")
		(at 148.59 -64.643 180)
		(property "Reference" "SR696"
			(at 0 0 180)
			(layer "F.SilkS")
			(hide yes)
			(effects
				(font
					(size 1.27 1.27)
				)
			)
		)
		(property "Value" "10KR2F-2-GP"
			(at 0.064008 -3.993896 180)
			(unlocked yes)
			(layer "F.Fab")
			(hide yes)
			(effects
				(font
					(size 1.016 1.016)
					(thickness 0.1524)
				)
			)
		)
		(property "Device Type" "R402H16"
			(at 0.064008 -5.517896 180)
			(unlocked yes)
			(layer "F.Fab")
			(hide yes)
			(effects
				(font
					(size 1.016 1.016)
					(thickness 0.1524)
				)
			)
		)
		(duplicate_pad_numbers_are_jumpers no)
		(fp_line
			(start 0.508 -0.9398)
			(end -0.508 -0.9398)
			(stroke
				(width 0.1524)
				(type default)
			)
			(layer "F.SilkS")
		)
		(fp_line
			(start -0.508 -0.9398)
			(end -0.508 0.9398)
			(stroke
				(width 0.1524)
				(type default)
			)
			(layer "F.SilkS")
		)
		(fp_rect
			(start -0.508 0.9398)
			(end 0.508 -0.9398)
			(stroke
				(width 0)
				(type default)
			)
			(fill no)
			(layer "F.CrtYd")
		)
		(fp_rect
			(start -0.508 0.9398)
			(end 0.508 -0.9398)
			(stroke
				(width 0)
				(type default)
			)
			(fill no)
			(layer "F.Fab")
		)
		(pad "1" smd custom
			(at 0 -0.4445 180)
			(size 0.1397 0.1397)
			(layers "F.Cu" "F.Mask" "F.Paste")
			(net "XM_ADDR_1")
			(options
				(clearance outline)
				(anchor circle)
			)
			(primitives
				(gr_poly
					(pts
						(arc
							(start -0.1778 -0.2794)
							(mid -0.249642 -0.249642)
							(end -0.2794 -0.1778)
						)
						(arc
							(start -0.2794 0.1778)
							(mid -0.249642 0.249642)
							(end -0.1778 0.2794)
						)
						(arc
							(start 0.1778 0.2794)
							(mid 0.249642 0.249642)
							(end 0.2794 0.1778)
						)
						(arc
							(start 0.2794 -0.1778)
							(mid 0.249642 -0.249642)
							(end 0.1778 -0.2794)
						)
					)
					(width 0)
					(fill yes)
				)
			)
		)
		(pad "2" smd custom
			(at 0 0.4445 180)
			(size 0.1397 0.1397)
			(layers "F.Cu" "F.Mask" "F.Paste")
			(net "GND")
			(options
				(clearance outline)
				(anchor circle)
			)
			(primitives
				(gr_poly
					(pts
						(arc
							(start -0.1778 -0.2794)
							(mid -0.249642 -0.249642)
							(end -0.2794 -0.1778)
						)
						(arc
							(start -0.2794 0.1778)
							(mid -0.249642 0.249642)
							(end -0.1778 0.2794)
						)
						(arc
							(start 0.1778 0.2794)
							(mid 0.249642 0.249642)
							(end 0.2794 0.1778)
						)
						(arc
							(start 0.2794 -0.1778)
							(mid 0.249642 -0.249642)
							(end 0.1778 -0.2794)
						)
					)
					(width 0)
					(fill yes)
				)
			)
		)
	)
	(footprint ""
		(layer "F.Cu")
		(at 342.040718 -157.838648 180)
		(property "Reference" "C163"
			(at 0 0 180)
			(layer "F.SilkS")
			(hide yes)
			(effects
				(font
					(size 1.27 1.27)
				)
			)
		)
		(property "Value" "SC1U10V2KX-4-GP"
			(at 1.1811 -2.7051 180)
			(unlocked yes)
			(layer "F.Fab")
			(hide yes)
			(effects
				(font
					(size 1.016 1.016)
					(thickness 0.1524)
				)
			)
		)
		(property "Device Type" "C402H22"
			(at 1.1811 -4.2291 180)
			(unlocked yes)
			(layer "F.Fab")
			(hide yes)
			(effects
				(font
					(size 1.016 1.016)
					(thickness 0.1524)
				)
			)
		)
		(duplicate_pad_numbers_are_jumpers no)
		(fp_rect
			(start -0.4318 0.9525)
			(end 0.4318 -0.9525)
			(stroke
				(width 0)
				(type default)
			)
			(fill no)
			(layer "F.CrtYd")
		)
		(fp_rect
			(start -0.4318 0.9525)
			(end 0.4318 -0.9525)
			(stroke
				(width 0)
				(type default)
			)
			(fill no)
			(layer "F.Fab")
		)
		(pad "1" smd custom
			(at 0 -0.4445 180)
			(size 0.1524 0.1524)
			(layers "F.Cu" "F.Mask" "F.Paste")
			(net "P3V3_STBY")
			(options
				(clearance outline)
				(anchor circle)
			)
			(primitives
				(gr_poly
					(pts
						(arc
							(start 0.3048 -0.2032)
							(mid 0.275042 -0.275042)
							(end 0.2032 -0.3048)
						)
						(arc
							(start -0.2032 -0.3048)
							(mid -0.275042 -0.275042)
							(end -0.3048 -0.2032)
						)
						(arc
							(start -0.3048 0.2032)
							(mid -0.275042 0.275042)
							(end -0.2032 0.3048)
						)
						(arc
							(start 0.2032 0.3048)
							(mid 0.275042 0.275042)
							(end 0.3048 0.2032)
						)
					)
					(width 0)
					(fill yes)
				)
			)
		)
		(pad "2" smd custom
			(at 0 0.4445 180)
			(size 0.1524 0.1524)
			(layers "F.Cu" "F.Mask" "F.Paste")
			(net "GND")
			(options
				(clearance outline)
				(anchor circle)
			)
			(primitives
				(gr_poly
					(pts
						(arc
							(start 0.3048 -0.2032)
							(mid 0.275042 -0.275042)
							(end 0.2032 -0.3048)
						)
						(arc
							(start -0.2032 -0.3048)
							(mid -0.275042 -0.275042)
							(end -0.3048 -0.2032)
						)
						(arc
							(start -0.3048 0.2032)
							(mid -0.275042 0.275042)
							(end -0.2032 0.3048)
						)
						(arc
							(start 0.2032 0.3048)
							(mid 0.275042 0.275042)
							(end 0.3048 0.2032)
						)
					)
					(width 0)
					(fill yes)
				)
			)
		)
	)
	(footprint ""
		(layer "F.Cu")
		(at 94.3356 -16.764 -90)
		(property "Reference" "SC946"
			(at 0 0 270)
			(layer "F.SilkS")
			(hide yes)
			(effects
				(font
					(size 1.27 1.27)
				)
			)
		)
		(property "Value" "SC22U6D3V5MX-2GP"
			(at -0.0762 -6.1214 270)
			(unlocked yes)
			(layer "F.Fab")
			(hide yes)
			(effects
				(font
					(size 1.016 1.016)
					(thickness 0.1524)
				)
			)
		)
		(property "Device Type" "C805H58"
			(at -0.0762 -8.1534 270)
			(unlocked yes)
			(layer "F.Fab")
			(hide yes)
			(effects
				(font
					(size 1.016 1.016)
					(thickness 0.1524)
				)
			)
		)
		(duplicate_pad_numbers_are_jumpers no)
		(fp_line
			(start 0.635 0)
			(end -0.635 0)
			(stroke
				(width 0.508)
				(type default)
			)
			(layer "F.SilkS")
		)
		(fp_rect
			(start -0.9652 1.778)
			(end 0.9652 -1.778)
			(stroke
				(width 0)
				(type default)
			)
			(fill no)
			(layer "F.CrtYd")
		)
		(fp_poly
			(pts
				(xy -0.9652 -1.778) (xy 0.9652 -1.778) (xy 0.9652 1.778) (xy -0.9652 1.778)
			)
			(stroke
				(width 0)
				(type default)
			)
			(fill no)
			(layer "F.Fab")
		)
		(pad "1" smd rect
			(at 0 -0.9652 270)
			(size 1.397 1.143)
			(layers "F.Cu" "F.Mask" "F.Paste")
			(net "PCE_AVDD")
		)
		(pad "2" smd rect
			(at 0 0.9652 270)
			(size 1.397 1.143)
			(layers "F.Cu" "F.Mask" "F.Paste")
			(net "GND")
		)
	)
)
